# T6G (Grand Teton) — schematic netlist excerpt (pin names and nets, part order shuffled) for the footprints in the layout excerpt that follows; sources: Cadence DE-HDL packaged netlist, KiCad conversion of 04192023_DAF0TMB3IC0_F0TG_MB_C_brd_V02_OCP.brd

C1037  Q_CAP  10UF 6.3V 20% X6S  pkg C0402  page 312 : A = P0V9_CPU0_RT3_2A ; B = GND
C1756  Q_CAP  0.1UF 25V 10% X7R  pkg 0402  page 127 : A = FM_GPU_PWRGD_ISO ; B = GND
PC576_5  Q_CAP  22UF 4V 20% X6S  pkg C0805  page 196 : A = PVDDCR_CPU0_P0 ; B = GND

(kicad_pcb
	(version 20260206)
	(generator "pcbnew")
	(generator_version "10.0")
	(general
		(thickness 1.6)
		(legacy_teardrops no)
	)
	(paper "A4")
	(title_block
		(title "04192023_DAF0TMB3IC0_F0TG_MB_C_brd_V02_OCP.brd")
		(comment 1 "Grand Teton / footprints 5133-5135 of 8354")
	)
	(layers
		(0 "F.Cu" signal "TOP")
		(4 "In1.Cu" signal "GND")
		(6 "In2.Cu" signal "IN1")
		(8 "In3.Cu" signal "GND1")
		(10 "In4.Cu" signal "IN2")
		(12 "In5.Cu" signal "GND2")
		(14 "In6.Cu" signal "IN3")
		(16 "In7.Cu" signal "GND3")
		(18 "In8.Cu" signal "VCC")
		(20 "In9.Cu" signal "VCC1")
		(22 "In10.Cu" signal "GND4")
		(24 "In11.Cu" signal "IN4")
		(26 "In12.Cu" signal "GND5")
		(28 "In13.Cu" signal "IN5")
		(30 "In14.Cu" signal "GND6")
		(32 "In15.Cu" signal "IN6")
		(34 "In16.Cu" signal "GND7")
		(2 "B.Cu" signal "BOTTOM")
		(9 "F.Adhes" user "F.Adhesive")
		(11 "B.Adhes" user "B.Adhesive")
		(13 "F.Paste" user "Package Geometry/Pastemask Top")
		(15 "B.Paste" user "Package Geometry/Pastemask Bottom")
		(5 "F.SilkS" user "Ref Des/Silkscreen Top")
		(7 "B.SilkS" user "Ref Des/Silkscreen Bottom")
		(1 "F.Mask" user "Board Geometry/Soldermask Top")
		(3 "B.Mask" user "Board Geometry/Soldermask Bottom")
		(17 "Dwgs.User" user "User.Drawings")
		(19 "Cmts.User" user "User.Comments")
		(21 "Eco1.User" user "User.Eco1")
		(23 "Eco2.User" user "User.Eco2")
		(25 "Edge.Cuts" user "Board Geometry/Outline")
		(27 "Margin" user)
		(31 "F.CrtYd" user "Package Geometry/Place Bound Top")
		(29 "B.CrtYd" user "Package Geometry/Place Bound Bottom")
		(35 "F.Fab" user "Ref Des/Assembly Top")
		(33 "B.Fab" user "Ref Des/Assembly Bottom")
	)
	(footprint ""
		(layer "B.Cu")
		(at 51.72964 -424.225212 90)
		(property "Reference" "C1756"
			(at 0 0 90)
			(layer "B.SilkS")
			(hide yes)
			(effects
				(font
					(size 1.27 1.27)
				)
				(justify mirror)
			)
		)
		(property "Value" ""
			(at 0 0 90)
			(layer "B.Fab")
			(effects
				(font
					(size 1.27 1.27)
				)
				(justify mirror)
			)
		)
		(duplicate_pad_numbers_are_jumpers no)
		(fp_line
			(start 0.7874 -0.4064)
			(end -0.7874 -0.4064)
			(stroke
				(width 0.1524)
				(type default)
			)
			(layer "B.SilkS")
		)
		(fp_line
			(start -0.7874 -0.4064)
			(end -0.7874 0.4064)
			(stroke
				(width 0.1524)
				(type default)
			)
			(layer "B.SilkS")
		)
		(fp_line
			(start 0.7874 0.4064)
			(end 0.7874 -0.4064)
			(stroke
				(width 0.1524)
				(type default)
			)
			(layer "B.SilkS")
		)
		(fp_line
			(start -0.7874 0.4064)
			(end 0.7874 0.4064)
			(stroke
				(width 0.1524)
				(type default)
			)
			(layer "B.SilkS")
		)
		(fp_line
			(start 0.67945 -0.305054)
			(end 0.12065 -0.305054)
			(stroke
				(width 0.1)
				(type default)
			)
			(layer "B.Fab")
		)
		(fp_line
			(start 0.12065 -0.305054)
			(end 0.12065 -0.2794)
			(stroke
				(width 0.1)
				(type default)
			)
			(layer "B.Fab")
		)
		(fp_line
			(start -0.12065 -0.3048)
			(end -0.67945 -0.3048)
			(stroke
				(width 0.1)
				(type default)
			)
			(layer "B.Fab")
		)
		(fp_line
			(start -0.67945 -0.3048)
			(end -0.67945 0.3048)
			(stroke
				(width 0.1)
				(type default)
			)
			(layer "B.Fab")
		)
		(fp_line
			(start 0.12065 -0.2794)
			(end -0.12065 -0.2794)
			(stroke
				(width 0.1)
				(type default)
			)
			(layer "B.Fab")
		)
		(fp_line
			(start -0.12065 -0.2794)
			(end -0.12065 -0.3048)
			(stroke
				(width 0.1)
				(type default)
			)
			(layer "B.Fab")
		)
		(fp_line
			(start 0.12065 0.2794)
			(end 0.12065 0.3048)
			(stroke
				(width 0.1)
				(type default)
			)
			(layer "B.Fab")
		)
		(fp_line
			(start -0.120396 0.2794)
			(end 0.12065 0.2794)
			(stroke
				(width 0.1)
				(type default)
			)
			(layer "B.Fab")
		)
		(fp_line
			(start 0.67945 0.3048)
			(end 0.67945 -0.305054)
			(stroke
				(width 0.1)
				(type default)
			)
			(layer "B.Fab")
		)
		(fp_line
			(start 0.12065 0.3048)
			(end 0.67945 0.3048)
			(stroke
				(width 0.1)
				(type default)
			)
			(layer "B.Fab")
		)
		(fp_line
			(start -0.120396 0.3048)
			(end -0.120396 0.2794)
			(stroke
				(width 0.1)
				(type default)
			)
			(layer "B.Fab")
		)
		(fp_line
			(start -0.67945 0.3048)
			(end -0.120396 0.3048)
			(stroke
				(width 0.1)
				(type default)
			)
			(layer "B.Fab")
		)
		(pad "1" smd circle
			(at 0.40005 0 270)
			(size 0 0)
			(layers "B.Cu" "B.Mask" "B.Paste")
			(net "FM_GPU_PWRGD_ISO")
		)
		(pad "2" smd circle
			(at -0.40005 0 270)
			(size 0 0)
			(layers "B.Cu" "B.Mask" "B.Paste")
			(net "GND")
		)
	)
	(footprint ""
		(layer "B.Cu")
		(at 370.491004 -398.942052 90)
		(property "Reference" "C1037"
			(at 0 0 90)
			(layer "B.SilkS")
			(hide yes)
			(effects
				(font
					(size 1.27 1.27)
				)
				(justify mirror)
			)
		)
		(property "Value" ""
			(at 0 0 90)
			(layer "B.Fab")
			(effects
				(font
					(size 1.27 1.27)
				)
				(justify mirror)
			)
		)
		(duplicate_pad_numbers_are_jumpers no)
		(fp_line
			(start 0.7874 -0.4064)
			(end -0.7874 -0.4064)
			(stroke
				(width 0.1524)
				(type default)
			)
			(layer "B.SilkS")
		)
		(fp_line
			(start -0.7874 -0.4064)
			(end -0.7874 0.4064)
			(stroke
				(width 0.1524)
				(type default)
			)
			(layer "B.SilkS")
		)
		(fp_line
			(start 0.7874 0.4064)
			(end 0.7874 -0.4064)
			(stroke
				(width 0.1524)
				(type default)
			)
			(layer "B.SilkS")
		)
		(fp_line
			(start -0.7874 0.4064)
			(end 0.7874 0.4064)
			(stroke
				(width 0.1524)
				(type default)
			)
			(layer "B.SilkS")
		)
		(fp_line
			(start 0.67945 -0.305054)
			(end 0.12065 -0.305054)
			(stroke
				(width 0.1)
				(type default)
			)
			(layer "B.Fab")
		)
		(fp_line
			(start 0.12065 -0.305054)
			(end 0.12065 -0.2794)
			(stroke
				(width 0.1)
				(type default)
			)
			(layer "B.Fab")
		)
		(fp_line
			(start -0.12065 -0.3048)
			(end -0.67945 -0.3048)
			(stroke
				(width 0.1)
				(type default)
			)
			(layer "B.Fab")
		)
		(fp_line
			(start -0.67945 -0.3048)
			(end -0.67945 0.3048)
			(stroke
				(width 0.1)
				(type default)
			)
			(layer "B.Fab")
		)
		(fp_line
			(start 0.12065 -0.2794)
			(end -0.12065 -0.2794)
			(stroke
				(width 0.1)
				(type default)
			)
			(layer "B.Fab")
		)
		(fp_line
			(start -0.12065 -0.2794)
			(end -0.12065 -0.3048)
			(stroke
				(width 0.1)
				(type default)
			)
			(layer "B.Fab")
		)
		(fp_line
			(start 0.12065 0.2794)
			(end 0.12065 0.3048)
			(stroke
				(width 0.1)
				(type default)
			)
			(layer "B.Fab")
		)
		(fp_line
			(start -0.120396 0.2794)
			(end 0.12065 0.2794)
			(stroke
				(width 0.1)
				(type default)
			)
			(layer "B.Fab")
		)
		(fp_line
			(start 0.67945 0.3048)
			(end 0.67945 -0.305054)
			(stroke
				(width 0.1)
				(type default)
			)
			(layer "B.Fab")
		)
		(fp_line
			(start 0.12065 0.3048)
			(end 0.67945 0.3048)
			(stroke
				(width 0.1)
				(type default)
			)
			(layer "B.Fab")
		)
		(fp_line
			(start -0.120396 0.3048)
			(end -0.120396 0.2794)
			(stroke
				(width 0.1)
				(type default)
			)
			(layer "B.Fab")
		)
		(fp_line
			(start -0.67945 0.3048)
			(end -0.120396 0.3048)
			(stroke
				(width 0.1)
				(type default)
			)
			(layer "B.Fab")
		)
		(pad "1" smd circle
			(at 0.40005 0 270)
			(size 0 0)
			(layers "B.Cu" "B.Mask" "B.Paste")
			(net "P0V9_CPU0_RT3_2A")
		)
		(pad "2" smd circle
			(at -0.40005 0 270)
			(size 0 0)
			(layers "B.Cu" "B.Mask" "B.Paste")
			(net "GND")
		)
	)
	(footprint ""
		(layer "B.Cu")
		(at 352.425 -177.912522 90)
		(property "Reference" "PC576_5"
			(at 0 0 90)
			(layer "B.SilkS")
			(hide yes)
			(effects
				(font
					(size 1.27 1.27)
				)
				(justify mirror)
			)
		)
		(property "Value" ""
			(at 0 0 90)
			(layer "B.Fab")
			(effects
				(font
					(size 1.27 1.27)
				)
				(justify mirror)
			)
		)
		(duplicate_pad_numbers_are_jumpers no)
		(fp_line
			(start 1.524 -0.762)
			(end -1.524 -0.762)
			(stroke
				(width 0.1524)
				(type default)
			)
			(layer "B.SilkS")
		)
		(fp_line
			(start -1.524 -0.762)
			(end -1.524 0.762)
			(stroke
				(width 0.1524)
				(type default)
			)
			(layer "B.SilkS")
		)
		(fp_line
			(start 1.524 0.762)
			(end 1.524 -0.762)
			(stroke
				(width 0.1524)
				(type default)
			)
			(layer "B.SilkS")
		)
		(fp_line
			(start -1.524 0.762)
			(end 1.524 0.762)
			(stroke
				(width 0.1524)
				(type default)
			)
			(layer "B.SilkS")
		)
		(fp_line
			(start 1.1049 -0.724916)
			(end 1.1049 0.724916)
			(stroke
				(width 0.1)
				(type default)
			)
			(layer "B.Fab")
		)
		(fp_line
			(start -1.1049 -0.724916)
			(end 1.1049 -0.724916)
			(stroke
				(width 0.1)
				(type default)
			)
			(layer "B.Fab")
		)
		(fp_line
			(start 1.1049 0.724916)
			(end -1.1049 0.724916)
			(stroke
				(width 0.1)
				(type default)
			)
			(layer "B.Fab")
		)
		(fp_line
			(start -1.1049 0.724916)
			(end -1.1049 -0.724916)
			(stroke
				(width 0.1)
				(type default)
			)
			(layer "B.Fab")
		)
		(pad "1" smd rect
			(at 0.889 0 90)
			(size 1.016 1.27)
			(layers "B.Cu" "B.Mask" "B.Paste")
			(net "PVDDCR_CPU0_P0")
		)
		(pad "2" smd rect
			(at -0.889 0 90)
			(size 1.016 1.27)
			(layers "B.Cu" "B.Mask" "B.Paste")
			(net "GND")
		)
	)
)
